(kicad_pcb
	(version 20260206)
	(generator "pcbnew")
	(generator_version "10.0")
	(general
		(thickness 1.6)
		(legacy_teardrops no)
	)
	(paper "A4")
	(title_block
		(title "Bryce Canyon_F.DPB_16315-1-OCP.brd")
		(comment 1 "Bryce Canyon / footprints 1721-1726 of 2223")
	)
	(layers
		(0 "F.Cu" signal "TOP")
		(4 "In1.Cu" signal "L2GND")
		(6 "In2.Cu" signal "L3")
		(8 "In3.Cu" signal "L4GND")
		(10 "In4.Cu" signal "L5")
		(12 "In5.Cu" signal "L6VCC")
		(14 "In6.Cu" signal "L7VCC")
		(16 "In7.Cu" signal "L8")
		(18 "In8.Cu" signal "L9GND")
		(20 "In9.Cu" signal "L10")
		(22 "In10.Cu" signal "L11GND")
		(2 "B.Cu" signal "BOTTOM")
		(9 "F.Adhes" user "F.Adhesive")
		(11 "B.Adhes" user "B.Adhesive")
		(13 "F.Paste" user "Package Geometry/Pastemask Top")
		(15 "B.Paste" user "Package Geometry/Pastemask Bottom")
		(5 "F.SilkS" user "Ref Des/Silkscreen Top")
		(7 "B.SilkS" user "Ref Des/Silkscreen Bottom")
		(1 "F.Mask" user "Board Geometry/Soldermask Top")
		(3 "B.Mask" user "Board Geometry/Soldermask Bottom")
		(17 "Dwgs.User" user "User.Drawings")
		(19 "Cmts.User" user "User.Comments")
		(21 "Eco1.User" user "User.Eco1")
		(23 "Eco2.User" user "User.Eco2")
		(25 "Edge.Cuts" user "Board Geometry/Outline")
		(27 "Margin" user)
		(31 "F.CrtYd" user "Package Geometry/Place Bound Top")
		(29 "B.CrtYd" user "Package Geometry/Place Bound Bottom")
		(35 "F.Fab" user "Ref Des/Assembly Top")
		(33 "B.Fab" user "Ref Des/Assembly Bottom")
	)
	(footprint ""
		(layer "F.Cu")
		(at 109.492796 -54.523894 90)
		(property "Reference" "C400"
			(at 0 0 90)
			(layer "F.SilkS")
			(hide yes)
			(effects
				(font
					(size 1.27 1.27)
				)
			)
		)
		(property "Value" "SCD033U25V2KX-GP"
			(at 1.1811 -2.7051 90)
			(unlocked yes)
			(layer "F.Fab")
			(hide yes)
			(effects
				(font
					(size 1.016 1.016)
					(thickness 0.1524)
				)
			)
		)
		(property "Device Type" "C402H22"
			(at 1.1811 -4.2291 90)
			(unlocked yes)
			(layer "F.Fab")
			(hide yes)
			(effects
				(font
					(size 1.016 1.016)
					(thickness 0.1524)
				)
			)
		)
		(duplicate_pad_numbers_are_jumpers no)
		(fp_rect
			(start -0.4318 0.9525)
			(end 0.4318 -0.9525)
			(stroke
				(width 0)
				(type default)
			)
			(fill no)
			(layer "F.CrtYd")
		)
		(fp_rect
			(start -0.4318 0.9525)
			(end 0.4318 -0.9525)
			(stroke
				(width 0)
				(type default)
			)
			(fill no)
			(layer "F.Fab")
		)
		(pad "1" smd custom
			(at 0 -0.4445 90)
			(size 0.1524 0.1524)
			(layers "F.Cu" "F.Mask" "F.Paste")
			(net "P12V_A")
			(options
				(clearance outline)
				(anchor circle)
			)
			(primitives
				(gr_poly
					(pts
						(arc
							(start 0.3048 -0.2032)
							(mid 0.275042 -0.275042)
							(end 0.2032 -0.3048)
						)
						(arc
							(start -0.2032 -0.3048)
							(mid -0.275042 -0.275042)
							(end -0.3048 -0.2032)
						)
						(arc
							(start -0.3048 0.2032)
							(mid -0.275042 0.275042)
							(end -0.2032 0.3048)
						)
						(arc
							(start 0.2032 0.3048)
							(mid 0.275042 0.275042)
							(end 0.3048 0.2032)
						)
					)
					(width 0)
					(fill yes)
				)
			)
		)
		(pad "2" smd custom
			(at 0 0.4445 90)
			(size 0.1524 0.1524)
			(layers "F.Cu" "F.Mask" "F.Paste")
			(net "SW_HDD_N27")
			(options
				(clearance outline)
				(anchor circle)
			)
			(primitives
				(gr_poly
					(pts
						(arc
							(start 0.3048 -0.2032)
							(mid 0.275042 -0.275042)
							(end 0.2032 -0.3048)
						)
						(arc
							(start -0.2032 -0.3048)
							(mid -0.275042 -0.275042)
							(end -0.3048 -0.2032)
						)
						(arc
							(start -0.3048 0.2032)
							(mid -0.275042 0.275042)
							(end -0.2032 0.3048)
						)
						(arc
							(start 0.2032 0.3048)
							(mid 0.275042 0.275042)
							(end 0.3048 0.2032)
						)
					)
					(width 0)
					(fill yes)
				)
			)
		)
	)
	(footprint ""
		(layer "F.Cu")
		(at 14.842998 -169.523918 90)
		(property "Reference" "C205"
			(at 0 0 90)
			(layer "F.SilkS")
			(hide yes)
			(effects
				(font
					(size 1.27 1.27)
				)
			)
		)
		(property "Value" "SCD033U25V2KX-GP"
			(at 1.1811 -2.7051 90)
			(unlocked yes)
			(layer "F.Fab")
			(hide yes)
			(effects
				(font
					(size 1.016 1.016)
					(thickness 0.1524)
				)
			)
		)
		(property "Device Type" "C402H22"
			(at 1.1811 -4.2291 90)
			(unlocked yes)
			(layer "F.Fab")
			(hide yes)
			(effects
				(font
					(size 1.016 1.016)
					(thickness 0.1524)
				)
			)
		)
		(duplicate_pad_numbers_are_jumpers no)
		(fp_rect
			(start -0.4318 0.9525)
			(end 0.4318 -0.9525)
			(stroke
				(width 0)
				(type default)
			)
			(fill no)
			(layer "F.CrtYd")
		)
		(fp_rect
			(start -0.4318 0.9525)
			(end 0.4318 -0.9525)
			(stroke
				(width 0)
				(type default)
			)
			(fill no)
			(layer "F.Fab")
		)
		(pad "1" smd custom
			(at 0 -0.4445 90)
			(size 0.1524 0.1524)
			(layers "F.Cu" "F.Mask" "F.Paste")
			(net "P12V_A")
			(options
				(clearance outline)
				(anchor circle)
			)
			(primitives
				(gr_poly
					(pts
						(arc
							(start 0.3048 -0.2032)
							(mid 0.275042 -0.275042)
							(end 0.2032 -0.3048)
						)
						(arc
							(start -0.2032 -0.3048)
							(mid -0.275042 -0.275042)
							(end -0.3048 -0.2032)
						)
						(arc
							(start -0.3048 0.2032)
							(mid -0.275042 0.275042)
							(end -0.2032 0.3048)
						)
						(arc
							(start 0.2032 0.3048)
							(mid 0.275042 0.275042)
							(end 0.3048 0.2032)
						)
					)
					(width 0)
					(fill yes)
				)
			)
		)
		(pad "2" smd custom
			(at 0 0.4445 90)
			(size 0.1524 0.1524)
			(layers "F.Cu" "F.Mask" "F.Paste")
			(net "SW_HDD_N12")
			(options
				(clearance outline)
				(anchor circle)
			)
			(primitives
				(gr_poly
					(pts
						(arc
							(start 0.3048 -0.2032)
							(mid 0.275042 -0.275042)
							(end 0.2032 -0.3048)
						)
						(arc
							(start -0.2032 -0.3048)
							(mid -0.275042 -0.275042)
							(end -0.3048 -0.2032)
						)
						(arc
							(start -0.3048 0.2032)
							(mid -0.275042 0.275042)
							(end -0.2032 0.3048)
						)
						(arc
							(start 0.2032 0.3048)
							(mid 0.275042 0.275042)
							(end 0.3048 0.2032)
						)
					)
					(width 0)
					(fill yes)
				)
			)
		)
	)
	(footprint ""
		(layer "F.Cu")
		(at 109.492796 -174.857918)
		(property "Reference" "Q92"
			(at 0 0 0)
			(layer "F.SilkS")
			(hide yes)
			(effects
				(font
					(size 1.27 1.27)
				)
			)
		)
		(property "Value" "AO4407AL-GP"
			(at -3.707384 -1.5367 0)
			(unlocked yes)
			(layer "F.Fab")
			(hide yes)
			(effects
				(font
					(size 1.016 1.016)
					(thickness 0.1524)
				)
			)
		)
		(property "Device Type" "SOIC8H69"
			(at -3.707384 -3.0607 0)
			(unlocked yes)
			(layer "F.Fab")
			(hide yes)
			(effects
				(font
					(size 1.016 1.016)
					(thickness 0.1524)
				)
			)
		)
		(duplicate_pad_numbers_are_jumpers no)
		(fp_line
			(start -2.7432 -1.4224)
			(end -2.7432 1.4224)
			(stroke
				(width 0.1524)
				(type default)
			)
			(layer "F.SilkS")
		)
		(fp_line
			(start -2.7432 1.4224)
			(end -2.6416 1.4224)
			(stroke
				(width 0.1524)
				(type default)
			)
			(layer "F.SilkS")
		)
		(fp_line
			(start -2.7432 1.4224)
			(end 2.1336 1.4224)
			(stroke
				(width 0.1524)
				(type default)
			)
			(layer "F.SilkS")
		)
		(fp_line
			(start -2.7178 -0.508)
			(end -2.1844 -0.0508)
			(stroke
				(width 0.1524)
				(type default)
			)
			(layer "F.SilkS")
		)
		(fp_line
			(start -2.6289 3.4417)
			(end -2.6289 1.4732)
			(stroke
				(width 0.381)
				(type default)
			)
			(layer "F.SilkS")
		)
		(fp_line
			(start -2.1844 -0.0508)
			(end -2.7178 0.508)
			(stroke
				(width 0.1524)
				(type default)
			)
			(layer "F.SilkS")
		)
		(fp_line
			(start 2.1336 -1.4224)
			(end -2.7432 -1.4224)
			(stroke
				(width 0.1524)
				(type default)
			)
			(layer "F.SilkS")
		)
		(fp_line
			(start 2.1336 1.4224)
			(end 2.1336 -1.4224)
			(stroke
				(width 0.1524)
				(type default)
			)
			(layer "F.SilkS")
		)
		(fp_poly
			(pts
				(xy -2.2098 -1.4224) (xy -2.2098 1.4224) (xy 2.2098 1.4224) (xy 2.2098 -1.4224)
			)
			(stroke
				(width 0)
				(type default)
			)
			(fill yes)
			(layer "F.SilkS")
		)
		(fp_rect
			(start -2.450084 2.999994)
			(end 2.450084 -2.999994)
			(stroke
				(width 0)
				(type default)
			)
			(fill no)
			(layer "F.CrtYd")
		)
		(fp_poly
			(pts
				(xy -2.8194 3.6322) (xy -2.8194 -3.6322) (xy 2.8194 -3.6322) (xy 2.8194 1.18364) (xy 2.450084 1.18364)
				(xy 2.450084 -2.999994) (xy -2.450084 -2.999994) (xy -2.450084 2.999994) (xy 2.450084 2.999994)
				(xy 2.450084 1.18618) (xy 2.8194 1.18618) (xy 2.8194 3.6322)
			)
			(stroke
				(width 0)
				(type default)
			)
			(fill no)
			(layer "F.CrtYd")
		)
		(fp_rect
			(start -2.8194 3.6322)
			(end 2.8194 -3.6322)
			(stroke
				(width 0)
				(type default)
			)
			(fill no)
			(layer "F.Fab")
		)
		(pad "1" smd rect
			(at -1.905 2.54)
			(size 0.635 1.651)
			(layers "F.Cu" "F.Mask" "F.Paste")
			(net "P12V_A")
		)
		(pad "2" smd rect
			(at -0.635 2.54)
			(size 0.635 1.651)
			(layers "F.Cu" "F.Mask" "F.Paste")
			(net "P12V_A")
		)
		(pad "3" smd rect
			(at 0.635 2.54)
			(size 0.635 1.651)
			(layers "F.Cu" "F.Mask" "F.Paste")
			(net "P12V_A")
		)
		(pad "4" smd rect
			(at 1.905 2.54)
			(size 0.635 1.651)
			(layers "F.Cu" "F.Mask" "F.Paste")
			(net "SW_HDD_N15")
		)
		(pad "5" smd rect
			(at 1.905 -2.54)
			(size 0.635 1.651)
			(layers "F.Cu" "F.Mask" "F.Paste")
			(net "P12V_HDD15")
		)
		(pad "6" smd rect
			(at 0.635 -2.54)
			(size 0.635 1.651)
			(layers "F.Cu" "F.Mask" "F.Paste")
			(net "P12V_HDD15")
		)
		(pad "7" smd rect
			(at -0.635 -2.54)
			(size 0.635 1.651)
			(layers "F.Cu" "F.Mask" "F.Paste")
			(net "P12V_HDD15")
		)
		(pad "8" smd rect
			(at -1.905 -2.54)
			(size 0.635 1.651)
			(layers "F.Cu" "F.Mask" "F.Paste")
			(net "P12V_HDD15")
		)
	)
	(footprint ""
		(layer "F.Cu")
		(at 130.328162 -304.331878 180)
		(property "Reference" "R251"
			(at 0 0 180)
			(layer "F.SilkS")
			(hide yes)
			(effects
				(font
					(size 1.27 1.27)
				)
			)
		)
		(property "Value" "130R3F-GP"
			(at -0.0254 -2.5146 180)
			(unlocked yes)
			(layer "F.Fab")
			(hide yes)
			(effects
				(font
					(size 1.016 1.016)
					(thickness 0.1524)
				)
			)
		)
		(property "Device Type" "R603H22"
			(at -0.0254 -4.0386 180)
			(unlocked yes)
			(layer "F.Fab")
			(hide yes)
			(effects
				(font
					(size 1.016 1.016)
					(thickness 0.1524)
				)
			)
		)
		(duplicate_pad_numbers_are_jumpers no)
		(fp_line
			(start 0.2032 0)
			(end 0.4826 0)
			(stroke
				(width 0.2032)
				(type default)
			)
			(layer "F.SilkS")
		)
		(fp_line
			(start -0.4826 0)
			(end -0.2032 0)
			(stroke
				(width 0.2032)
				(type default)
			)
			(layer "F.SilkS")
		)
		(fp_rect
			(start -0.5842 1.3335)
			(end 0.5842 -1.3335)
			(stroke
				(width 0)
				(type default)
			)
			(fill no)
			(layer "F.CrtYd")
		)
		(fp_rect
			(start -0.5842 1.3335)
			(end 0.5842 -1.3335)
			(stroke
				(width 0)
				(type default)
			)
			(fill no)
			(layer "F.Fab")
		)
		(pad "1" smd custom
			(at 0 -0.762 180)
			(size 0.2159 0.2159)
			(layers "F.Cu" "F.Mask" "F.Paste")
			(net "P5V_B")
			(options
				(clearance outline)
				(anchor circle)
			)
			(primitives
				(gr_poly
					(pts
						(arc
							(start -0.3302 -0.4318)
							(mid -0.402042 -0.402042)
							(end -0.4318 -0.3302)
						)
						(arc
							(start -0.4318 0.3302)
							(mid -0.402042 0.402042)
							(end -0.3302 0.4318)
						)
						(arc
							(start 0.3302 0.4318)
							(mid 0.402042 0.402042)
							(end 0.4318 0.3302)
						)
						(arc
							(start 0.4318 -0.3302)
							(mid 0.402042 -0.402042)
							(end 0.3302 -0.4318)
						)
					)
					(width 0)
					(fill yes)
				)
			)
		)
		(pad "2" smd custom
			(at 0 0.762 180)
			(size 0.2159 0.2159)
			(layers "F.Cu" "F.Mask" "F.Paste")
			(net "FLT_HDD28")
			(options
				(clearance outline)
				(anchor circle)
			)
			(primitives
				(gr_poly
					(pts
						(arc
							(start -0.3302 -0.4318)
							(mid -0.402042 -0.402042)
							(end -0.4318 -0.3302)
						)
						(arc
							(start -0.4318 0.3302)
							(mid -0.402042 0.402042)
							(end -0.3302 0.4318)
						)
						(arc
							(start 0.3302 0.4318)
							(mid 0.402042 0.402042)
							(end 0.4318 0.3302)
						)
						(arc
							(start 0.4318 -0.3302)
							(mid 0.402042 -0.402042)
							(end 0.3302 -0.4318)
						)
					)
					(width 0)
					(fill yes)
				)
			)
		)
	)
	(footprint ""
		(layer "F.Cu")
		(at 161.997898 -176.127918 90)
		(property "Reference" "C253"
			(at 0 0 90)
			(layer "F.SilkS")
			(hide yes)
			(effects
				(font
					(size 1.27 1.27)
				)
			)
		)
		(property "Value" "SCD01U50V2KX-1GP"
			(at 1.1811 -2.7051 90)
			(unlocked yes)
			(layer "F.Fab")
			(hide yes)
			(effects
				(font
					(size 1.016 1.016)
					(thickness 0.1524)
				)
			)
		)
		(property "Device Type" "C402H22"
			(at 1.1811 -4.2291 90)
			(unlocked yes)
			(layer "F.Fab")
			(hide yes)
			(effects
				(font
					(size 1.016 1.016)
					(thickness 0.1524)
				)
			)
		)
		(duplicate_pad_numbers_are_jumpers no)
		(fp_rect
			(start -0.4318 0.9525)
			(end 0.4318 -0.9525)
			(stroke
				(width 0)
				(type default)
			)
			(fill no)
			(layer "F.CrtYd")
		)
		(fp_rect
			(start -0.4318 0.9525)
			(end 0.4318 -0.9525)
			(stroke
				(width 0)
				(type default)
			)
			(fill no)
			(layer "F.Fab")
		)
		(pad "1" smd custom
			(at 0 -0.4445 90)
			(size 0.1524 0.1524)
			(layers "F.Cu" "F.Mask" "F.Paste")
			(net "HDD_PRSNT_16")
			(options
				(clearance outline)
				(anchor circle)
			)
			(primitives
				(gr_poly
					(pts
						(arc
							(start 0.3048 -0.2032)
							(mid 0.275042 -0.275042)
							(end 0.2032 -0.3048)
						)
						(arc
							(start -0.2032 -0.3048)
							(mid -0.275042 -0.275042)
							(end -0.3048 -0.2032)
						)
						(arc
							(start -0.3048 0.2032)
							(mid -0.275042 0.275042)
							(end -0.2032 0.3048)
						)
						(arc
							(start 0.2032 0.3048)
							(mid 0.275042 0.275042)
							(end 0.3048 0.2032)
						)
					)
					(width 0)
					(fill yes)
				)
			)
		)
		(pad "2" smd custom
			(at 0 0.4445 90)
			(size 0.1524 0.1524)
			(layers "F.Cu" "F.Mask" "F.Paste")
			(net "GND")
			(options
				(clearance outline)
				(anchor circle)
			)
			(primitives
				(gr_poly
					(pts
						(arc
							(start 0.3048 -0.2032)
							(mid 0.275042 -0.275042)
							(end 0.2032 -0.3048)
						)
						(arc
							(start -0.2032 -0.3048)
							(mid -0.275042 -0.275042)
							(end -0.3048 -0.2032)
						)
						(arc
							(start -0.3048 0.2032)
							(mid -0.275042 0.275042)
							(end -0.2032 0.3048)
						)
						(arc
							(start 0.2032 0.3048)
							(mid 0.275042 0.275042)
							(end 0.3048 0.2032)
						)
					)
					(width 0)
					(fill yes)
				)
			)
		)
	)
	(footprint ""
		(layer "F.Cu")
		(at 455.227944 -242.722654 180)
		(property "Reference" "Q274"
			(at 0 0 180)
			(layer "F.SilkS")
			(hide yes)
			(effects
				(font
					(size 1.27 1.27)
				)
			)
		)
		(property "Value" "SSM3K324R-GP"
			(at 0.127 -8.9662 180)
			(unlocked yes)
			(layer "F.Fab")
			(hide yes)
			(effects
				(font
					(size 1.016 1.016)
					(thickness 0.1524)
				)
			)
		)
		(property "Device Type" "SOT23DGS2D4H35"
			(at 0.127 -10.4902 180)
			(unlocked yes)
			(layer "F.Fab")
			(hide yes)
			(effects
				(font
					(size 1.016 1.016)
					(thickness 0.1524)
				)
			)
		)
		(duplicate_pad_numbers_are_jumpers no)
		(fp_line
			(start 1.651 1.778)
			(end 1.651 -1.778)
			(stroke
				(width 0.1524)
				(type default)
			)
			(layer "F.SilkS")
		)
		(fp_line
			(start 1.651 -1.778)
			(end -1.651 -1.778)
			(stroke
				(width 0.1524)
				(type default)
			)
			(layer "F.SilkS")
		)
		(fp_line
			(start -1.651 1.778)
			(end 1.651 1.778)
			(stroke
				(width 0.1524)
				(type default)
			)
			(layer "F.SilkS")
		)
		(fp_line
			(start -1.651 -1.778)
			(end -1.651 1.778)
			(stroke
				(width 0.1524)
				(type default)
			)
			(layer "F.SilkS")
		)
		(fp_poly
			(pts
				(xy -1.778 1.8796) (xy -1.778 -1.8796) (xy 1.778 -1.8796) (xy 1.778 1.8796)
			)
			(stroke
				(width 0)
				(type default)
			)
			(fill no)
			(layer "F.CrtYd")
		)
		(fp_poly
			(pts
				(xy -1.778 1.8796) (xy -1.778 -1.8796) (xy 1.778 -1.8796) (xy 1.778 1.8796)
			)
			(stroke
				(width 0)
				(type default)
			)
			(fill no)
			(layer "F.Fab")
		)
		(pad "D" smd custom
			(at 0 -0.9525 180)
			(size 0.1905 0.1905)
			(layers "F.Cu" "F.Mask" "F.Paste")
			(net "DRV_ACT_11_N")
			(options
				(clearance outline)
				(anchor circle)
			)
			(primitives
				(gr_poly
					(pts
						(arc
							(start -0.1778 0.5715)
							(mid -0.321484 0.511984)
							(end -0.381 0.3683)
						)
						(arc
							(start -0.381 -0.3683)
							(mid -0.321484 -0.511984)
							(end -0.1778 -0.5715)
						)
						(arc
							(start 0.1778 -0.5715)
							(mid 0.321484 -0.511984)
							(end 0.381 -0.3683)
						)
						(arc
							(start 0.381 0.3683)
							(mid 0.321484 0.511984)
							(end 0.1778 0.5715)
						)
					)
					(width 0)
					(fill yes)
				)
			)
		)
		(pad "G" smd custom
			(at -0.98425 0.9525 180)
			(size 0.1905 0.1905)
			(layers "F.Cu" "F.Mask" "F.Paste")
			(net "DRIVE_A_11_ACT")
			(options
				(clearance outline)
				(anchor circle)
			)
			(primitives
				(gr_poly
					(pts
						(arc
							(start -0.1778 0.5715)
							(mid -0.321484 0.511984)
							(end -0.381 0.3683)
						)
						(arc
							(start -0.381 -0.3683)
							(mid -0.321484 -0.511984)
							(end -0.1778 -0.5715)
						)
						(arc
							(start 0.1778 -0.5715)
							(mid 0.321484 -0.511984)
							(end 0.381 -0.3683)
						)
						(arc
							(start 0.381 0.3683)
							(mid 0.321484 0.511984)
							(end 0.1778 0.5715)
						)
					)
					(width 0)
					(fill yes)
				)
			)
		)
		(pad "S" smd custom
			(at 0.98425 0.9525 180)
			(size 0.1905 0.1905)
			(layers "F.Cu" "F.Mask" "F.Paste")
			(net "GND")
			(options
				(clearance outline)
				(anchor circle)
			)
			(primitives
				(gr_poly
					(pts
						(arc
							(start -0.1778 0.5715)
							(mid -0.321484 0.511984)
							(end -0.381 0.3683)
						)
						(arc
							(start -0.381 -0.3683)
							(mid -0.321484 -0.511984)
							(end -0.1778 -0.5715)
						)
						(arc
							(start 0.1778 -0.5715)
							(mid 0.321484 -0.511984)
							(end 0.381 -0.3683)
						)
						(arc
							(start 0.381 0.3683)
							(mid 0.321484 0.511984)
							(end 0.1778 0.5715)
						)
					)
					(width 0)
					(fill yes)
				)
			)
		)
	)
)
